(kicad_pcb
	(version 20260206)
	(generator "pcbnew")
	(generator_version "10.0")
	(general
		(thickness 1.6)
		(legacy_teardrops no)
	)
	(paper "A4")
	(title_block
		(title "01162023_DA0F0TEBIF0_F0T_Expander_BD_F_brd_V02_OCP.brd")
		(comment 1 "Grand Teton / footprints 1797-1801 of 9728")
	)
	(layers
		(0 "F.Cu" signal "TOP")
		(4 "In1.Cu" signal "GND")
		(6 "In2.Cu" signal "VCC")
		(8 "In3.Cu" signal "VCC1")
		(10 "In4.Cu" signal "GND1")
		(12 "In5.Cu" signal "IN1")
		(14 "In6.Cu" signal "GND2")
		(16 "In7.Cu" signal "IN2")
		(18 "In8.Cu" signal "GND3")
		(20 "In9.Cu" signal "IN3")
		(22 "In10.Cu" signal "GND4")
		(24 "In11.Cu" signal "IN4")
		(26 "In12.Cu" signal "GND5")
		(28 "In13.Cu" signal "IN5")
		(30 "In14.Cu" signal "GND6")
		(32 "In15.Cu" signal "IN6")
		(34 "In16.Cu" signal "GND7")
		(2 "B.Cu" signal "BOTTOM")
		(9 "F.Adhes" user "F.Adhesive")
		(11 "B.Adhes" user "B.Adhesive")
		(13 "F.Paste" user "Package Geometry/Pastemask Top")
		(15 "B.Paste" user "Package Geometry/Pastemask Bottom")
		(5 "F.SilkS" user "Ref Des/Silkscreen Top")
		(7 "B.SilkS" user "Ref Des/Silkscreen Bottom")
		(1 "F.Mask" user "Board Geometry/Soldermask Top")
		(3 "B.Mask" user "Board Geometry/Soldermask Bottom")
		(17 "Dwgs.User" user "User.Drawings")
		(19 "Cmts.User" user "User.Comments")
		(21 "Eco1.User" user "User.Eco1")
		(23 "Eco2.User" user "User.Eco2")
		(25 "Edge.Cuts" user "Board Geometry/Outline")
		(27 "Margin" user)
		(31 "F.CrtYd" user "Package Geometry/Place Bound Top")
		(29 "B.CrtYd" user "Package Geometry/Place Bound Bottom")
		(35 "F.Fab" user "Ref Des/Assembly Top")
		(33 "B.Fab" user "Ref Des/Assembly Bottom")
	)
	(footprint ""
		(layer "F.Cu")
		(at 57.866788 -52.543456 180)
		(property "Reference" "PC524"
			(at 0 0 180)
			(layer "F.SilkS")
			(hide yes)
			(effects
				(font
					(size 1.27 1.27)
				)
			)
		)
		(property "Value" ""
			(at 0 0 180)
			(layer "F.Fab")
			(effects
				(font
					(size 1.27 1.27)
				)
			)
		)
		(duplicate_pad_numbers_are_jumpers no)
		(fp_line
			(start 0.7874 0.4064)
			(end -0.7874 0.4064)
			(stroke
				(width 0.1524)
				(type default)
			)
			(layer "F.SilkS")
		)
		(fp_line
			(start 0.7874 -0.4064)
			(end 0.7874 0.4064)
			(stroke
				(width 0.1524)
				(type default)
			)
			(layer "F.SilkS")
		)
		(fp_line
			(start -0.7874 0.4064)
			(end -0.7874 -0.4064)
			(stroke
				(width 0.1524)
				(type default)
			)
			(layer "F.SilkS")
		)
		(fp_line
			(start -0.7874 -0.4064)
			(end 0.7874 -0.4064)
			(stroke
				(width 0.1524)
				(type default)
			)
			(layer "F.SilkS")
		)
		(fp_line
			(start 0.67945 0.3048)
			(end 0.120396 0.3048)
			(stroke
				(width 0.1)
				(type default)
			)
			(layer "F.Fab")
		)
		(fp_line
			(start 0.67945 -0.3048)
			(end 0.67945 0.3048)
			(stroke
				(width 0.1)
				(type default)
			)
			(layer "F.Fab")
		)
		(fp_line
			(start 0.12065 -0.2794)
			(end 0.12065 -0.3048)
			(stroke
				(width 0.1)
				(type default)
			)
			(layer "F.Fab")
		)
		(fp_line
			(start 0.12065 -0.3048)
			(end 0.67945 -0.3048)
			(stroke
				(width 0.1)
				(type default)
			)
			(layer "F.Fab")
		)
		(fp_line
			(start 0.120396 0.3048)
			(end 0.120396 0.2794)
			(stroke
				(width 0.1)
				(type default)
			)
			(layer "F.Fab")
		)
		(fp_line
			(start 0.120396 0.2794)
			(end -0.12065 0.2794)
			(stroke
				(width 0.1)
				(type default)
			)
			(layer "F.Fab")
		)
		(fp_line
			(start -0.12065 0.3048)
			(end -0.67945 0.3048)
			(stroke
				(width 0.1)
				(type default)
			)
			(layer "F.Fab")
		)
		(fp_line
			(start -0.12065 0.2794)
			(end -0.12065 0.3048)
			(stroke
				(width 0.1)
				(type default)
			)
			(layer "F.Fab")
		)
		(fp_line
			(start -0.12065 -0.2794)
			(end 0.12065 -0.2794)
			(stroke
				(width 0.1)
				(type default)
			)
			(layer "F.Fab")
		)
		(fp_line
			(start -0.12065 -0.305054)
			(end -0.12065 -0.2794)
			(stroke
				(width 0.1)
				(type default)
			)
			(layer "F.Fab")
		)
		(fp_line
			(start -0.67945 0.3048)
			(end -0.67945 -0.305054)
			(stroke
				(width 0.1)
				(type default)
			)
			(layer "F.Fab")
		)
		(fp_line
			(start -0.67945 -0.305054)
			(end -0.12065 -0.305054)
			(stroke
				(width 0.1)
				(type default)
			)
			(layer "F.Fab")
		)
		(pad "1" smd circle
			(at -0.40005 0 180)
			(size 0 0)
			(layers "F.Cu" "F.Mask" "F.Paste")
			(net "P3V3_SSD2")
		)
		(pad "2" smd circle
			(at 0.40005 0 180)
			(size 0 0)
			(layers "F.Cu" "F.Mask" "F.Paste")
			(net "GND")
		)
	)
	(footprint ""
		(layer "F.Cu")
		(at 328.01814 -95.31477 90)
		(property "Reference" "R856"
			(at 0 0 90)
			(layer "F.SilkS")
			(hide yes)
			(effects
				(font
					(size 1.27 1.27)
				)
			)
		)
		(property "Value" ""
			(at 0 0 90)
			(layer "F.Fab")
			(effects
				(font
					(size 1.27 1.27)
				)
			)
		)
		(duplicate_pad_numbers_are_jumpers no)
		(fp_line
			(start 0.7874 -0.4064)
			(end 0.7874 0.4064)
			(stroke
				(width 0.1524)
				(type default)
			)
			(layer "F.SilkS")
		)
		(fp_line
			(start -0.7874 -0.4064)
			(end 0.7874 -0.4064)
			(stroke
				(width 0.1524)
				(type default)
			)
			(layer "F.SilkS")
		)
		(fp_line
			(start 0.7874 0.4064)
			(end -0.7874 0.4064)
			(stroke
				(width 0.1524)
				(type default)
			)
			(layer "F.SilkS")
		)
		(fp_line
			(start -0.7874 0.4064)
			(end -0.7874 -0.4064)
			(stroke
				(width 0.1524)
				(type default)
			)
			(layer "F.SilkS")
		)
		(fp_line
			(start -0.12065 -0.305054)
			(end -0.12065 -0.2794)
			(stroke
				(width 0.1)
				(type default)
			)
			(layer "F.Fab")
		)
		(fp_line
			(start -0.67945 -0.305054)
			(end -0.12065 -0.305054)
			(stroke
				(width 0.1)
				(type default)
			)
			(layer "F.Fab")
		)
		(fp_line
			(start 0.67945 -0.3048)
			(end 0.67945 0.3048)
			(stroke
				(width 0.1)
				(type default)
			)
			(layer "F.Fab")
		)
		(fp_line
			(start 0.12065 -0.3048)
			(end 0.67945 -0.3048)
			(stroke
				(width 0.1)
				(type default)
			)
			(layer "F.Fab")
		)
		(fp_line
			(start 0.12065 -0.2794)
			(end 0.12065 -0.3048)
			(stroke
				(width 0.1)
				(type default)
			)
			(layer "F.Fab")
		)
		(fp_line
			(start -0.12065 -0.2794)
			(end 0.12065 -0.2794)
			(stroke
				(width 0.1)
				(type default)
			)
			(layer "F.Fab")
		)
		(fp_line
			(start 0.120396 0.2794)
			(end -0.12065 0.2794)
			(stroke
				(width 0.1)
				(type default)
			)
			(layer "F.Fab")
		)
		(fp_line
			(start -0.12065 0.2794)
			(end -0.12065 0.3048)
			(stroke
				(width 0.1)
				(type default)
			)
			(layer "F.Fab")
		)
		(fp_line
			(start 0.67945 0.3048)
			(end 0.120396 0.3048)
			(stroke
				(width 0.1)
				(type default)
			)
			(layer "F.Fab")
		)
		(fp_line
			(start 0.120396 0.3048)
			(end 0.120396 0.2794)
			(stroke
				(width 0.1)
				(type default)
			)
			(layer "F.Fab")
		)
		(fp_line
			(start -0.12065 0.3048)
			(end -0.67945 0.3048)
			(stroke
				(width 0.1)
				(type default)
			)
			(layer "F.Fab")
		)
		(fp_line
			(start -0.67945 0.3048)
			(end -0.67945 -0.305054)
			(stroke
				(width 0.1)
				(type default)
			)
			(layer "F.Fab")
		)
		(pad "1" smd circle
			(at -0.40005 0 90)
			(size 0 0)
			(layers "F.Cu" "F.Mask" "F.Paste")
			(net "P3V3_AUX")
		)
		(pad "2" smd circle
			(at 0.40005 0 90)
			(size 0 0)
			(layers "F.Cu" "F.Mask" "F.Paste")
			(net "PWRGD_P12V_NIC5")
		)
	)
	(footprint ""
		(layer "F.Cu")
		(at 361.188 -188.214 180)
		(property "Reference" "R4644"
			(at 0 0 180)
			(layer "F.SilkS")
			(hide yes)
			(effects
				(font
					(size 1.27 1.27)
				)
			)
		)
		(property "Value" ""
			(at 0 0 180)
			(layer "F.Fab")
			(effects
				(font
					(size 1.27 1.27)
				)
			)
		)
		(duplicate_pad_numbers_are_jumpers no)
		(fp_line
			(start 0.7874 0.4064)
			(end -0.7874 0.4064)
			(stroke
				(width 0.1524)
				(type default)
			)
			(layer "F.SilkS")
		)
		(fp_line
			(start 0.7874 -0.4064)
			(end 0.7874 0.4064)
			(stroke
				(width 0.1524)
				(type default)
			)
			(layer "F.SilkS")
		)
		(fp_line
			(start -0.7874 0.4064)
			(end -0.7874 -0.4064)
			(stroke
				(width 0.1524)
				(type default)
			)
			(layer "F.SilkS")
		)
		(fp_line
			(start -0.7874 -0.4064)
			(end 0.7874 -0.4064)
			(stroke
				(width 0.1524)
				(type default)
			)
			(layer "F.SilkS")
		)
		(fp_line
			(start 0.67945 0.3048)
			(end 0.120396 0.3048)
			(stroke
				(width 0.1)
				(type default)
			)
			(layer "F.Fab")
		)
		(fp_line
			(start 0.67945 -0.3048)
			(end 0.67945 0.3048)
			(stroke
				(width 0.1)
				(type default)
			)
			(layer "F.Fab")
		)
		(fp_line
			(start 0.12065 -0.2794)
			(end 0.12065 -0.3048)
			(stroke
				(width 0.1)
				(type default)
			)
			(layer "F.Fab")
		)
		(fp_line
			(start 0.12065 -0.3048)
			(end 0.67945 -0.3048)
			(stroke
				(width 0.1)
				(type default)
			)
			(layer "F.Fab")
		)
		(fp_line
			(start 0.120396 0.3048)
			(end 0.120396 0.2794)
			(stroke
				(width 0.1)
				(type default)
			)
			(layer "F.Fab")
		)
		(fp_line
			(start 0.120396 0.2794)
			(end -0.12065 0.2794)
			(stroke
				(width 0.1)
				(type default)
			)
			(layer "F.Fab")
		)
		(fp_line
			(start -0.12065 0.3048)
			(end -0.67945 0.3048)
			(stroke
				(width 0.1)
				(type default)
			)
			(layer "F.Fab")
		)
		(fp_line
			(start -0.12065 0.2794)
			(end -0.12065 0.3048)
			(stroke
				(width 0.1)
				(type default)
			)
			(layer "F.Fab")
		)
		(fp_line
			(start -0.12065 -0.2794)
			(end 0.12065 -0.2794)
			(stroke
				(width 0.1)
				(type default)
			)
			(layer "F.Fab")
		)
		(fp_line
			(start -0.12065 -0.305054)
			(end -0.12065 -0.2794)
			(stroke
				(width 0.1)
				(type default)
			)
			(layer "F.Fab")
		)
		(fp_line
			(start -0.67945 0.3048)
			(end -0.67945 -0.305054)
			(stroke
				(width 0.1)
				(type default)
			)
			(layer "F.Fab")
		)
		(fp_line
			(start -0.67945 -0.305054)
			(end -0.12065 -0.305054)
			(stroke
				(width 0.1)
				(type default)
			)
			(layer "F.Fab")
		)
		(pad "1" smd circle
			(at -0.40005 0 180)
			(size 0 0)
			(layers "F.Cu" "F.Mask" "F.Paste")
			(net "RST_PEX_SSD2_PERST_N")
		)
		(pad "2" smd circle
			(at 0.40005 0 180)
			(size 0 0)
			(layers "F.Cu" "F.Mask" "F.Paste")
			(net "RST_PEX_SSD2_PERST_R_N")
		)
	)
	(footprint ""
		(layer "F.Cu")
		(at 5.656326 -66.567812 180)
		(property "Reference" "R5868"
			(at 0 0 180)
			(layer "F.SilkS")
			(hide yes)
			(effects
				(font
					(size 1.27 1.27)
				)
			)
		)
		(property "Value" ""
			(at 0 0 180)
			(layer "F.Fab")
			(effects
				(font
					(size 1.27 1.27)
				)
			)
		)
		(duplicate_pad_numbers_are_jumpers no)
		(fp_line
			(start 0.7874 0.4064)
			(end -0.7874 0.4064)
			(stroke
				(width 0.1524)
				(type default)
			)
			(layer "F.SilkS")
		)
		(fp_line
			(start 0.7874 -0.4064)
			(end 0.7874 0.4064)
			(stroke
				(width 0.1524)
				(type default)
			)
			(layer "F.SilkS")
		)
		(fp_line
			(start -0.7874 0.4064)
			(end -0.7874 -0.4064)
			(stroke
				(width 0.1524)
				(type default)
			)
			(layer "F.SilkS")
		)
		(fp_line
			(start -0.7874 -0.4064)
			(end 0.7874 -0.4064)
			(stroke
				(width 0.1524)
				(type default)
			)
			(layer "F.SilkS")
		)
		(fp_line
			(start 0.67945 0.3048)
			(end 0.120396 0.3048)
			(stroke
				(width 0.1)
				(type default)
			)
			(layer "F.Fab")
		)
		(fp_line
			(start 0.67945 -0.3048)
			(end 0.67945 0.3048)
			(stroke
				(width 0.1)
				(type default)
			)
			(layer "F.Fab")
		)
		(fp_line
			(start 0.12065 -0.2794)
			(end 0.12065 -0.3048)
			(stroke
				(width 0.1)
				(type default)
			)
			(layer "F.Fab")
		)
		(fp_line
			(start 0.12065 -0.3048)
			(end 0.67945 -0.3048)
			(stroke
				(width 0.1)
				(type default)
			)
			(layer "F.Fab")
		)
		(fp_line
			(start 0.120396 0.3048)
			(end 0.120396 0.2794)
			(stroke
				(width 0.1)
				(type default)
			)
			(layer "F.Fab")
		)
		(fp_line
			(start 0.120396 0.2794)
			(end -0.12065 0.2794)
			(stroke
				(width 0.1)
				(type default)
			)
			(layer "F.Fab")
		)
		(fp_line
			(start -0.12065 0.3048)
			(end -0.67945 0.3048)
			(stroke
				(width 0.1)
				(type default)
			)
			(layer "F.Fab")
		)
		(fp_line
			(start -0.12065 0.2794)
			(end -0.12065 0.3048)
			(stroke
				(width 0.1)
				(type default)
			)
			(layer "F.Fab")
		)
		(fp_line
			(start -0.12065 -0.2794)
			(end 0.12065 -0.2794)
			(stroke
				(width 0.1)
				(type default)
			)
			(layer "F.Fab")
		)
		(fp_line
			(start -0.12065 -0.305054)
			(end -0.12065 -0.2794)
			(stroke
				(width 0.1)
				(type default)
			)
			(layer "F.Fab")
		)
		(fp_line
			(start -0.67945 0.3048)
			(end -0.67945 -0.305054)
			(stroke
				(width 0.1)
				(type default)
			)
			(layer "F.Fab")
		)
		(fp_line
			(start -0.67945 -0.305054)
			(end -0.12065 -0.305054)
			(stroke
				(width 0.1)
				(type default)
			)
			(layer "F.Fab")
		)
		(pad "1" smd circle
			(at -0.40005 0 180)
			(size 0 0)
			(layers "F.Cu" "F.Mask" "F.Paste")
			(net "P3V3_AUX")
		)
		(pad "2" smd circle
			(at 0.40005 0 180)
			(size 0 0)
			(layers "F.Cu" "F.Mask" "F.Paste")
			(net "PWRGD_P3V3_SSD0_D")
		)
	)
	(footprint ""
		(layer "F.Cu")
		(at 400.567906 -54.067456)
		(property "Reference" "PR230"
			(at 0 0 0)
			(layer "F.SilkS")
			(hide yes)
			(effects
				(font
					(size 1.27 1.27)
				)
			)
		)
		(property "Value" ""
			(at 0 0 0)
			(layer "F.Fab")
			(effects
				(font
					(size 1.27 1.27)
				)
			)
		)
		(duplicate_pad_numbers_are_jumpers no)
		(fp_line
			(start -0.7874 -0.4064)
			(end 0.7874 -0.4064)
			(stroke
				(width 0.1524)
				(type default)
			)
			(layer "F.SilkS")
		)
		(fp_line
			(start -0.7874 0.4064)
			(end -0.7874 -0.4064)
			(stroke
				(width 0.1524)
				(type default)
			)
			(layer "F.SilkS")
		)
		(fp_line
			(start 0.7874 -0.4064)
			(end 0.7874 0.4064)
			(stroke
				(width 0.1524)
				(type default)
			)
			(layer "F.SilkS")
		)
		(fp_line
			(start 0.7874 0.4064)
			(end -0.7874 0.4064)
			(stroke
				(width 0.1524)
				(type default)
			)
			(layer "F.SilkS")
		)
		(fp_line
			(start -0.67945 -0.305054)
			(end -0.12065 -0.305054)
			(stroke
				(width 0.1)
				(type default)
			)
			(layer "F.Fab")
		)
		(fp_line
			(start -0.67945 0.3048)
			(end -0.67945 -0.305054)
			(stroke
				(width 0.1)
				(type default)
			)
			(layer "F.Fab")
		)
		(fp_line
			(start -0.12065 -0.305054)
			(end -0.12065 -0.2794)
			(stroke
				(width 0.1)
				(type default)
			)
			(layer "F.Fab")
		)
		(fp_line
			(start -0.12065 -0.2794)
			(end 0.12065 -0.2794)
			(stroke
				(width 0.1)
				(type default)
			)
			(layer "F.Fab")
		)
		(fp_line
			(start -0.12065 0.2794)
			(end -0.12065 0.3048)
			(stroke
				(width 0.1)
				(type default)
			)
			(layer "F.Fab")
		)
		(fp_line
			(start -0.12065 0.3048)
			(end -0.67945 0.3048)
			(stroke
				(width 0.1)
				(type default)
			)
			(layer "F.Fab")
		)
		(fp_line
			(start 0.120396 0.2794)
			(end -0.12065 0.2794)
			(stroke
				(width 0.1)
				(type default)
			)
			(layer "F.Fab")
		)
		(fp_line
			(start 0.120396 0.3048)
			(end 0.120396 0.2794)
			(stroke
				(width 0.1)
				(type default)
			)
			(layer "F.Fab")
		)
		(fp_line
			(start 0.12065 -0.3048)
			(end 0.67945 -0.3048)
			(stroke
				(width 0.1)
				(type default)
			)
			(layer "F.Fab")
		)
		(fp_line
			(start 0.12065 -0.2794)
			(end 0.12065 -0.3048)
			(stroke
				(width 0.1)
				(type default)
			)
			(layer "F.Fab")
		)
		(fp_line
			(start 0.67945 -0.3048)
			(end 0.67945 0.3048)
			(stroke
				(width 0.1)
				(type default)
			)
			(layer "F.Fab")
		)
		(fp_line
			(start 0.67945 0.3048)
			(end 0.120396 0.3048)
			(stroke
				(width 0.1)
				(type default)
			)
			(layer "F.Fab")
		)
		(pad "1" smd circle
			(at -0.40005 0)
			(size 0 0)
			(layers "F.Cu" "F.Mask" "F.Paste")
			(net "P12V_SSD13_OCP")
		)
		(pad "2" smd circle
			(at 0.40005 0)
			(size 0 0)
			(layers "F.Cu" "F.Mask" "F.Paste")
			(net "GND")
		)
	)
)
